# S9S_MB_2U (Grand Teton) — schematic netlist excerpt (pin names and nets, part order shuffled) for the footprints in the layout excerpt that follows; sources: Cadence DE-HDL packaged netlist, KiCad conversion of 03242023_DA0F0TMBIJ0_F0T_Motherboard_J_brd_V01_OCP.brd

R4502  Q_RES  33.2 1% CHIP  pkg 0402LF  page 131 : A = SMB_HOST_3V3AUX_SCL_R4 ; B = SMB_HOST_3V3AUX_XDP_R_SCL
R3876  Q_RES  49.9 1% CHIP  pkg 0402LF  page 83 : A = I3C_SPD_DDRABCD_CPU0_LVC1_SCL_1 ; B = I3C_SPD_DDRABCD_CPU0_LVC1_SCL

(kicad_pcb
	(version 20260206)
	(generator "pcbnew")
	(generator_version "10.0")
	(general
		(thickness 1.6)
		(legacy_teardrops no)
	)
	(paper "A4")
	(title_block
		(title "03242023_DA0F0TMBIJ0_F0T_Motherboard_J_brd_V01_OCP.brd")
		(comment 1 "Grand Teton / footprints 5041-5042 of 6105")
	)
	(layers
		(0 "F.Cu" signal "TOP")
		(4 "In1.Cu" signal "GND")
		(6 "In2.Cu" signal "IN1")
		(8 "In3.Cu" signal "GND1")
		(10 "In4.Cu" signal "IN2")
		(12 "In5.Cu" signal "GND2")
		(14 "In6.Cu" signal "IN3")
		(16 "In7.Cu" signal "GND3")
		(18 "In8.Cu" signal "VCC")
		(20 "In9.Cu" signal "VCC1")
		(22 "In10.Cu" signal "GND4")
		(24 "In11.Cu" signal "IN4")
		(26 "In12.Cu" signal "GND5")
		(28 "In13.Cu" signal "IN5")
		(30 "In14.Cu" signal "GND6")
		(32 "In15.Cu" signal "IN6")
		(34 "In16.Cu" signal "GND7")
		(2 "B.Cu" signal "BOTTOM")
		(9 "F.Adhes" user "F.Adhesive")
		(11 "B.Adhes" user "B.Adhesive")
		(13 "F.Paste" user "Package Geometry/Pastemask Top")
		(15 "B.Paste" user "Package Geometry/Pastemask Bottom")
		(5 "F.SilkS" user "Ref Des/Silkscreen Top")
		(7 "B.SilkS" user "Ref Des/Silkscreen Bottom")
		(1 "F.Mask" user "Board Geometry/Soldermask Top")
		(3 "B.Mask" user "Board Geometry/Soldermask Bottom")
		(17 "Dwgs.User" user "User.Drawings")
		(19 "Cmts.User" user "User.Comments")
		(21 "Eco1.User" user "User.Eco1")
		(23 "Eco2.User" user "User.Eco2")
		(25 "Edge.Cuts" user "Board Geometry/Outline")
		(27 "Margin" user)
		(31 "F.CrtYd" user "Package Geometry/Place Bound Top")
		(29 "B.CrtYd" user "Package Geometry/Place Bound Bottom")
		(35 "F.Fab" user "Ref Des/Assembly Top")
		(33 "B.Fab" user "Ref Des/Assembly Bottom")
	)
	(footprint ""
		(layer "B.Cu")
		(at 305.181 -317.159386 45)
		(property "Reference" "R3876"
			(at 0 0 45)
			(layer "B.SilkS")
			(hide yes)
			(effects
				(font
					(size 1.27 1.27)
				)
				(justify mirror)
			)
		)
		(property "Value" ""
			(at 0 0 45)
			(layer "B.Fab")
			(effects
				(font
					(size 1.27 1.27)
				)
				(justify mirror)
			)
		)
		(duplicate_pad_numbers_are_jumpers no)
		(fp_line
			(start -0.787389 -0.406267)
			(end -0.787389 0.406267)
			(stroke
				(width 0.1524)
				(type default)
			)
			(layer "B.SilkS")
		)
		(fp_line
			(start -0.787389 0.406267)
			(end 0.787389 0.406267)
			(stroke
				(width 0.1524)
				(type default)
			)
			(layer "B.SilkS")
		)
		(fp_line
			(start 0.787389 -0.406267)
			(end -0.787389 -0.406267)
			(stroke
				(width 0.1524)
				(type default)
			)
			(layer "B.SilkS")
		)
		(fp_line
			(start 0.787389 0.406267)
			(end 0.787389 -0.406267)
			(stroke
				(width 0.1524)
				(type default)
			)
			(layer "B.SilkS")
		)
		(fp_line
			(start -0.679446 -0.30479)
			(end -0.679446 0.30479)
			(stroke
				(width 0.1)
				(type default)
			)
			(layer "B.Fab")
		)
		(fp_line
			(start -0.120515 -0.30479)
			(end -0.679446 -0.30479)
			(stroke
				(width 0.1)
				(type default)
			)
			(layer "B.Fab")
		)
		(fp_line
			(start -0.120695 -0.279466)
			(end -0.120515 -0.30479)
			(stroke
				(width 0.1)
				(type default)
			)
			(layer "B.Fab")
		)
		(fp_line
			(start -0.679446 0.30479)
			(end -0.120515 0.30479)
			(stroke
				(width 0.1)
				(type default)
			)
			(layer "B.Fab")
		)
		(fp_line
			(start 0.120695 -0.304969)
			(end 0.120695 -0.279466)
			(stroke
				(width 0.1)
				(type default)
			)
			(layer "B.Fab")
		)
		(fp_line
			(start 0.120695 -0.279466)
			(end -0.120695 -0.279466)
			(stroke
				(width 0.1)
				(type default)
			)
			(layer "B.Fab")
		)
		(fp_line
			(start -0.120335 0.279466)
			(end 0.120695 0.279466)
			(stroke
				(width 0.1)
				(type default)
			)
			(layer "B.Fab")
		)
		(fp_line
			(start -0.120515 0.30479)
			(end -0.120335 0.279466)
			(stroke
				(width 0.1)
				(type default)
			)
			(layer "B.Fab")
		)
		(fp_line
			(start 0.679446 -0.305149)
			(end 0.120695 -0.304969)
			(stroke
				(width 0.1)
				(type default)
			)
			(layer "B.Fab")
		)
		(fp_line
			(start 0.120695 0.279466)
			(end 0.120515 0.30479)
			(stroke
				(width 0.1)
				(type default)
			)
			(layer "B.Fab")
		)
		(fp_line
			(start 0.120515 0.30479)
			(end 0.679446 0.30479)
			(stroke
				(width 0.1)
				(type default)
			)
			(layer "B.Fab")
		)
		(fp_line
			(start 0.679446 0.30479)
			(end 0.679446 -0.305149)
			(stroke
				(width 0.1)
				(type default)
			)
			(layer "B.Fab")
		)
		(pad "1" smd circle
			(at 0.40005 0 225)
			(size 0 0)
			(layers "B.Cu" "B.Mask" "B.Paste")
			(net "I3C_SPD_DDRABCD_CPU0_LVC1_SCL_1")
		)
		(pad "2" smd circle
			(at -0.40005 0 225)
			(size 0 0)
			(layers "B.Cu" "B.Mask" "B.Paste")
			(net "I3C_SPD_DDRABCD_CPU0_LVC1_SCL")
		)
	)
	(footprint ""
		(layer "B.Cu")
		(at 238.75238 -132.508752 90)
		(property "Reference" "R4502"
			(at 0 0 90)
			(layer "B.SilkS")
			(hide yes)
			(effects
				(font
					(size 1.27 1.27)
				)
				(justify mirror)
			)
		)
		(property "Value" ""
			(at 0 0 90)
			(layer "B.Fab")
			(effects
				(font
					(size 1.27 1.27)
				)
				(justify mirror)
			)
		)
		(duplicate_pad_numbers_are_jumpers no)
		(fp_line
			(start 0.7874 -0.4064)
			(end -0.7874 -0.4064)
			(stroke
				(width 0.1524)
				(type default)
			)
			(layer "B.SilkS")
		)
		(fp_line
			(start -0.7874 -0.4064)
			(end -0.7874 0.4064)
			(stroke
				(width 0.1524)
				(type default)
			)
			(layer "B.SilkS")
		)
		(fp_line
			(start 0.7874 0.4064)
			(end 0.7874 -0.4064)
			(stroke
				(width 0.1524)
				(type default)
			)
			(layer "B.SilkS")
		)
		(fp_line
			(start -0.7874 0.4064)
			(end 0.7874 0.4064)
			(stroke
				(width 0.1524)
				(type default)
			)
			(layer "B.SilkS")
		)
		(fp_line
			(start 0.67945 -0.305054)
			(end 0.12065 -0.305054)
			(stroke
				(width 0.1)
				(type default)
			)
			(layer "B.Fab")
		)
		(fp_line
			(start 0.12065 -0.305054)
			(end 0.12065 -0.2794)
			(stroke
				(width 0.1)
				(type default)
			)
			(layer "B.Fab")
		)
		(fp_line
			(start -0.12065 -0.3048)
			(end -0.67945 -0.3048)
			(stroke
				(width 0.1)
				(type default)
			)
			(layer "B.Fab")
		)
		(fp_line
			(start -0.67945 -0.3048)
			(end -0.67945 0.3048)
			(stroke
				(width 0.1)
				(type default)
			)
			(layer "B.Fab")
		)
		(fp_line
			(start 0.12065 -0.2794)
			(end -0.12065 -0.2794)
			(stroke
				(width 0.1)
				(type default)
			)
			(layer "B.Fab")
		)
		(fp_line
			(start -0.12065 -0.2794)
			(end -0.12065 -0.3048)
			(stroke
				(width 0.1)
				(type default)
			)
			(layer "B.Fab")
		)
		(fp_line
			(start 0.12065 0.2794)
			(end 0.12065 0.3048)
			(stroke
				(width 0.1)
				(type default)
			)
			(layer "B.Fab")
		)
		(fp_line
			(start -0.120396 0.2794)
			(end 0.12065 0.2794)
			(stroke
				(width 0.1)
				(type default)
			)
			(layer "B.Fab")
		)
		(fp_line
			(start 0.67945 0.3048)
			(end 0.67945 -0.305054)
			(stroke
				(width 0.1)
				(type default)
			)
			(layer "B.Fab")
		)
		(fp_line
			(start 0.12065 0.3048)
			(end 0.67945 0.3048)
			(stroke
				(width 0.1)
				(type default)
			)
			(layer "B.Fab")
		)
		(fp_line
			(start -0.120396 0.3048)
			(end -0.120396 0.2794)
			(stroke
				(width 0.1)
				(type default)
			)
			(layer "B.Fab")
		)
		(fp_line
			(start -0.67945 0.3048)
			(end -0.120396 0.3048)
			(stroke
				(width 0.1)
				(type default)
			)
			(layer "B.Fab")
		)
		(pad "1" smd circle
			(at 0.40005 0 270)
			(size 0 0)
			(layers "B.Cu" "B.Mask" "B.Paste")
			(net "SMB_HOST_3V3AUX_SCL_R4")
		)
		(pad "2" smd circle
			(at -0.40005 0 270)
			(size 0 0)
			(layers "B.Cu" "B.Mask" "B.Paste")
			(net "SMB_HOST_3V3AUX_XDP_R_SCL")
		)
	)
)
